# S9S_MB_2U (Grand Teton) — schematic netlist excerpt (pin names and nets, part order shuffled) for the footprints in the layout excerpt that follows; sources: Cadence DE-HDL packaged netlist, KiCad conversion of 03242023_DA0F0TMBIJ0_F0T_Motherboard_J_brd_V01_OCP.brd

R3189  Q_RES  33.2 1% CHIP  pkg 0402LF  page 161 : A = RST_OCP_V3_2_BUF_N ; B = RST_PERST3_OCP_V3_2_N
R2570  Q_RES  0 5% CHIP  pkg 0402LF  page 292 : A = FM_PVCCFA_EHV_CPU1_EN ; B = PVCCFA_EHV_CPU1_EN_R

(kicad_pcb
	(version 20260206)
	(generator "pcbnew")
	(generator_version "10.0")
	(general
		(thickness 1.6)
		(legacy_teardrops no)
	)
	(paper "A4")
	(title_block
		(title "03242023_DA0F0TMBIJ0_F0T_Motherboard_J_brd_V01_OCP.brd")
		(comment 1 "Grand Teton / footprints 1617-1618 of 6105")
	)
	(layers
		(0 "F.Cu" signal "TOP")
		(4 "In1.Cu" signal "GND")
		(6 "In2.Cu" signal "IN1")
		(8 "In3.Cu" signal "GND1")
		(10 "In4.Cu" signal "IN2")
		(12 "In5.Cu" signal "GND2")
		(14 "In6.Cu" signal "IN3")
		(16 "In7.Cu" signal "GND3")
		(18 "In8.Cu" signal "VCC")
		(20 "In9.Cu" signal "VCC1")
		(22 "In10.Cu" signal "GND4")
		(24 "In11.Cu" signal "IN4")
		(26 "In12.Cu" signal "GND5")
		(28 "In13.Cu" signal "IN5")
		(30 "In14.Cu" signal "GND6")
		(32 "In15.Cu" signal "IN6")
		(34 "In16.Cu" signal "GND7")
		(2 "B.Cu" signal "BOTTOM")
		(9 "F.Adhes" user "F.Adhesive")
		(11 "B.Adhes" user "B.Adhesive")
		(13 "F.Paste" user "Package Geometry/Pastemask Top")
		(15 "B.Paste" user "Package Geometry/Pastemask Bottom")
		(5 "F.SilkS" user "Ref Des/Silkscreen Top")
		(7 "B.SilkS" user "Ref Des/Silkscreen Bottom")
		(1 "F.Mask" user "Board Geometry/Soldermask Top")
		(3 "B.Mask" user "Board Geometry/Soldermask Bottom")
		(17 "Dwgs.User" user "User.Drawings")
		(19 "Cmts.User" user "User.Comments")
		(21 "Eco1.User" user "User.Eco1")
		(23 "Eco2.User" user "User.Eco2")
		(25 "Edge.Cuts" user "Board Geometry/Outline")
		(27 "Margin" user)
		(31 "F.CrtYd" user "Package Geometry/Place Bound Top")
		(29 "B.CrtYd" user "Package Geometry/Place Bound Bottom")
		(35 "F.Fab" user "Ref Des/Assembly Top")
		(33 "B.Fab" user "Ref Des/Assembly Bottom")
	)
	(footprint ""
		(layer "F.Cu")
		(at 36.956238 -133.81482 180)
		(property "Reference" "R2570"
			(at 0 0 180)
			(layer "F.SilkS")
			(hide yes)
			(effects
				(font
					(size 1.27 1.27)
				)
			)
		)
		(property "Value" ""
			(at 0 0 180)
			(layer "F.Fab")
			(effects
				(font
					(size 1.27 1.27)
				)
			)
		)
		(duplicate_pad_numbers_are_jumpers no)
		(fp_line
			(start 0.7874 0.4064)
			(end -0.7874 0.4064)
			(stroke
				(width 0.1524)
				(type default)
			)
			(layer "F.SilkS")
		)
		(fp_line
			(start 0.7874 -0.4064)
			(end 0.7874 0.4064)
			(stroke
				(width 0.1524)
				(type default)
			)
			(layer "F.SilkS")
		)
		(fp_line
			(start -0.7874 0.4064)
			(end -0.7874 -0.4064)
			(stroke
				(width 0.1524)
				(type default)
			)
			(layer "F.SilkS")
		)
		(fp_line
			(start -0.7874 -0.4064)
			(end 0.7874 -0.4064)
			(stroke
				(width 0.1524)
				(type default)
			)
			(layer "F.SilkS")
		)
		(fp_line
			(start 0.67945 0.3048)
			(end 0.120396 0.3048)
			(stroke
				(width 0.1)
				(type default)
			)
			(layer "F.Fab")
		)
		(fp_line
			(start 0.67945 -0.3048)
			(end 0.67945 0.3048)
			(stroke
				(width 0.1)
				(type default)
			)
			(layer "F.Fab")
		)
		(fp_line
			(start 0.12065 -0.2794)
			(end 0.12065 -0.3048)
			(stroke
				(width 0.1)
				(type default)
			)
			(layer "F.Fab")
		)
		(fp_line
			(start 0.12065 -0.3048)
			(end 0.67945 -0.3048)
			(stroke
				(width 0.1)
				(type default)
			)
			(layer "F.Fab")
		)
		(fp_line
			(start 0.120396 0.3048)
			(end 0.120396 0.2794)
			(stroke
				(width 0.1)
				(type default)
			)
			(layer "F.Fab")
		)
		(fp_line
			(start 0.120396 0.2794)
			(end -0.12065 0.2794)
			(stroke
				(width 0.1)
				(type default)
			)
			(layer "F.Fab")
		)
		(fp_line
			(start -0.12065 0.3048)
			(end -0.67945 0.3048)
			(stroke
				(width 0.1)
				(type default)
			)
			(layer "F.Fab")
		)
		(fp_line
			(start -0.12065 0.2794)
			(end -0.12065 0.3048)
			(stroke
				(width 0.1)
				(type default)
			)
			(layer "F.Fab")
		)
		(fp_line
			(start -0.12065 -0.2794)
			(end 0.12065 -0.2794)
			(stroke
				(width 0.1)
				(type default)
			)
			(layer "F.Fab")
		)
		(fp_line
			(start -0.12065 -0.305054)
			(end -0.12065 -0.2794)
			(stroke
				(width 0.1)
				(type default)
			)
			(layer "F.Fab")
		)
		(fp_line
			(start -0.67945 0.3048)
			(end -0.67945 -0.305054)
			(stroke
				(width 0.1)
				(type default)
			)
			(layer "F.Fab")
		)
		(fp_line
			(start -0.67945 -0.305054)
			(end -0.12065 -0.305054)
			(stroke
				(width 0.1)
				(type default)
			)
			(layer "F.Fab")
		)
		(pad "1" smd circle
			(at -0.40005 0 180)
			(size 0 0)
			(layers "F.Cu" "F.Mask" "F.Paste")
			(net "FM_PVCCFA_EHV_CPU1_EN")
		)
		(pad "2" smd circle
			(at 0.40005 0 180)
			(size 0 0)
			(layers "F.Cu" "F.Mask" "F.Paste")
			(net "PVCCFA_EHV_CPU1_EN_R")
		)
	)
	(footprint ""
		(layer "F.Cu")
		(at 106.476038 -38.983158)
		(property "Reference" "R3189"
			(at 0 0 0)
			(layer "F.SilkS")
			(hide yes)
			(effects
				(font
					(size 1.27 1.27)
				)
			)
		)
		(property "Value" ""
			(at 0 0 0)
			(layer "F.Fab")
			(effects
				(font
					(size 1.27 1.27)
				)
			)
		)
		(duplicate_pad_numbers_are_jumpers no)
		(fp_line
			(start -0.7874 -0.4064)
			(end 0.7874 -0.4064)
			(stroke
				(width 0.1524)
				(type default)
			)
			(layer "F.SilkS")
		)
		(fp_line
			(start -0.7874 0.4064)
			(end -0.7874 -0.4064)
			(stroke
				(width 0.1524)
				(type default)
			)
			(layer "F.SilkS")
		)
		(fp_line
			(start 0.7874 -0.4064)
			(end 0.7874 0.4064)
			(stroke
				(width 0.1524)
				(type default)
			)
			(layer "F.SilkS")
		)
		(fp_line
			(start 0.7874 0.4064)
			(end -0.7874 0.4064)
			(stroke
				(width 0.1524)
				(type default)
			)
			(layer "F.SilkS")
		)
		(fp_line
			(start -0.67945 -0.305054)
			(end -0.12065 -0.305054)
			(stroke
				(width 0.1)
				(type default)
			)
			(layer "F.Fab")
		)
		(fp_line
			(start -0.67945 0.3048)
			(end -0.67945 -0.305054)
			(stroke
				(width 0.1)
				(type default)
			)
			(layer "F.Fab")
		)
		(fp_line
			(start -0.12065 -0.305054)
			(end -0.12065 -0.2794)
			(stroke
				(width 0.1)
				(type default)
			)
			(layer "F.Fab")
		)
		(fp_line
			(start -0.12065 -0.2794)
			(end 0.12065 -0.2794)
			(stroke
				(width 0.1)
				(type default)
			)
			(layer "F.Fab")
		)
		(fp_line
			(start -0.12065 0.2794)
			(end -0.12065 0.3048)
			(stroke
				(width 0.1)
				(type default)
			)
			(layer "F.Fab")
		)
		(fp_line
			(start -0.12065 0.3048)
			(end -0.67945 0.3048)
			(stroke
				(width 0.1)
				(type default)
			)
			(layer "F.Fab")
		)
		(fp_line
			(start 0.120396 0.2794)
			(end -0.12065 0.2794)
			(stroke
				(width 0.1)
				(type default)
			)
			(layer "F.Fab")
		)
		(fp_line
			(start 0.120396 0.3048)
			(end 0.120396 0.2794)
			(stroke
				(width 0.1)
				(type default)
			)
			(layer "F.Fab")
		)
		(fp_line
			(start 0.12065 -0.3048)
			(end 0.67945 -0.3048)
			(stroke
				(width 0.1)
				(type default)
			)
			(layer "F.Fab")
		)
		(fp_line
			(start 0.12065 -0.2794)
			(end 0.12065 -0.3048)
			(stroke
				(width 0.1)
				(type default)
			)
			(layer "F.Fab")
		)
		(fp_line
			(start 0.67945 -0.3048)
			(end 0.67945 0.3048)
			(stroke
				(width 0.1)
				(type default)
			)
			(layer "F.Fab")
		)
		(fp_line
			(start 0.67945 0.3048)
			(end 0.120396 0.3048)
			(stroke
				(width 0.1)
				(type default)
			)
			(layer "F.Fab")
		)
		(pad "1" smd circle
			(at -0.40005 0)
			(size 0 0)
			(layers "F.Cu" "F.Mask" "F.Paste")
			(net "RST_OCP_V3_2_BUF_N")
		)
		(pad "2" smd circle
			(at 0.40005 0)
			(size 0 0)
			(layers "F.Cu" "F.Mask" "F.Paste")
			(net "RST_PERST3_OCP_V3_2_N")
		)
	)
)
